(kicad_pcb
	(version 20260206)
	(generator "pcbnew")
	(generator_version "10.0")
	(general
		(thickness 1.6)
		(legacy_teardrops no)
	)
	(paper "A4")
	(title_block
		(title "01162023_DA0F0TEBIF0_F0T_Expander_BD_F_brd_V02_OCP.brd")
		(comment 1 "Grand Teton / footprint 1438 of 9728 (J13), pads 78-142 of 142")
	)
	(layers
		(0 "F.Cu" signal "TOP")
		(4 "In1.Cu" signal "GND")
		(6 "In2.Cu" signal "VCC")
		(8 "In3.Cu" signal "VCC1")
		(10 "In4.Cu" signal "GND1")
		(12 "In5.Cu" signal "IN1")
		(14 "In6.Cu" signal "GND2")
		(16 "In7.Cu" signal "IN2")
		(18 "In8.Cu" signal "GND3")
		(20 "In9.Cu" signal "IN3")
		(22 "In10.Cu" signal "GND4")
		(24 "In11.Cu" signal "IN4")
		(26 "In12.Cu" signal "GND5")
		(28 "In13.Cu" signal "IN5")
		(30 "In14.Cu" signal "GND6")
		(32 "In15.Cu" signal "IN6")
		(34 "In16.Cu" signal "GND7")
		(2 "B.Cu" signal "BOTTOM")
		(9 "F.Adhes" user "F.Adhesive")
		(11 "B.Adhes" user "B.Adhesive")
		(13 "F.Paste" user "Package Geometry/Pastemask Top")
		(15 "B.Paste" user "Package Geometry/Pastemask Bottom")
		(5 "F.SilkS" user "Ref Des/Silkscreen Top")
		(7 "B.SilkS" user "Ref Des/Silkscreen Bottom")
		(1 "F.Mask" user "Board Geometry/Soldermask Top")
		(3 "B.Mask" user "Board Geometry/Soldermask Bottom")
		(17 "Dwgs.User" user "User.Drawings")
		(19 "Cmts.User" user "User.Comments")
		(21 "Eco1.User" user "User.Eco1")
		(23 "Eco2.User" user "User.Eco2")
		(25 "Edge.Cuts" user "Board Geometry/Outline")
		(27 "Margin" user)
		(31 "F.CrtYd" user "Package Geometry/Place Bound Top")
		(29 "B.CrtYd" user "Package Geometry/Place Bound Bottom")
		(35 "F.Fab" user "Ref Des/Assembly Top")
		(33 "B.Fab" user "Ref Des/Assembly Bottom")
	)
	(footprint ""
		(layer "F.Cu")
		(at 331.490066 -412.090108)
		(property "Reference" "J13"
			(at -5.874512 6.282436 90)
			(unlocked yes)
			(layer "F.SilkS")
			(effects
				(font
					(size 2.032 1.524)
					(thickness 0.1524)
				)
				(justify left)
			)
		)
		(property "Value" ""
			(at 0 0 0)
			(layer "F.Fab")
			(effects
				(font
					(size 1.27 1.27)
				)
			)
		)
		(duplicate_pad_numbers_are_jumpers no)
		(pad "N2_3" thru_hole circle
			(at 4.400042 27.29992 180)
			(size 0.906272 0.906272)
			(drill 0.499872)
			(layers "*.Cu" "*.Mask")
			(remove_unused_layers no)
			(net "GND")
			(clearance 0.0508)
			(thermal_gap 0.0508)
		)
		(pad "N2_5" thru_hole circle
			(at 8.800084 27.29992 180)
			(size 0.906272 0.906272)
			(drill 0.499872)
			(layers "*.Cu" "*.Mask")
			(remove_unused_layers no)
			(net "GND")
			(clearance 0.0508)
			(thermal_gap 0.0508)
		)
		(pad "N2_7" thru_hole circle
			(at 13.199872 27.29992 180)
			(size 0.906272 0.906272)
			(drill 0.499872)
			(layers "*.Cu" "*.Mask")
			(remove_unused_layers no)
			(net "GND")
			(clearance 0.0508)
			(thermal_gap 0.0508)
		)
		(pad "N2_9" thru_hole circle
			(at 17.599914 27.29992 180)
			(size 0.906272 0.906272)
			(drill 0.499872)
			(layers "*.Cu" "*.Mask")
			(remove_unused_layers no)
			(net "GND")
			(clearance 0.0508)
			(thermal_gap 0.0508)
		)
		(pad "N10" thru_hole circle
			(at 19.800062 27.500072 180)
			(size 0.71628 0.71628)
			(drill 0.30988)
			(layers "*.Cu" "*.Mask")
			(remove_unused_layers no)
			(net "Net_8888")
			(clearance 0.0508)
			(thermal_gap 0.0508)
		)
		(pad "O9" thru_hole circle
			(at 17.599914 28.599892 180)
			(size 0.71628 0.71628)
			(drill 0.30988)
			(layers "*.Cu" "*.Mask")
			(remove_unused_layers no)
			(net "Net_8886")
			(clearance 0.0508)
			(thermal_gap 0.0508)
		)
		(pad "O10" thru_hole circle
			(at 19.800062 28.800044 180)
			(size 0.71628 0.71628)
			(drill 0.30988)
			(layers "*.Cu" "*.Mask")
			(remove_unused_layers no)
			(net "Net_8887")
			(clearance 0.0508)
			(thermal_gap 0.0508)
		)
		(pad "P2" thru_hole circle
			(at 2.199894 30.100016 180)
			(size 0.906272 0.906272)
			(drill 0.499872)
			(layers "*.Cu" "*.Mask")
			(remove_unused_layers no)
			(net "GND")
			(clearance 0.0508)
			(thermal_gap 0.0508)
		)
		(pad "P4" thru_hole circle
			(at 6.599936 30.100016 180)
			(size 0.906272 0.906272)
			(drill 0.499872)
			(layers "*.Cu" "*.Mask")
			(remove_unused_layers no)
			(net "GND")
			(clearance 0.0508)
			(thermal_gap 0.0508)
		)
		(pad "P6" thru_hole circle
			(at 10.999978 30.100016 180)
			(size 0.906272 0.906272)
			(drill 0.499872)
			(layers "*.Cu" "*.Mask")
			(remove_unused_layers no)
			(net "GND")
			(clearance 0.0508)
			(thermal_gap 0.0508)
		)
		(pad "P8" thru_hole circle
			(at 15.40002 30.100016 180)
			(size 0.906272 0.906272)
			(drill 0.499872)
			(layers "*.Cu" "*.Mask")
			(remove_unused_layers no)
			(net "GND")
			(clearance 0.0508)
			(thermal_gap 0.0508)
		)
		(pad "P9" thru_hole circle
			(at 17.599914 29.900118 180)
			(size 0.71628 0.71628)
			(drill 0.30988)
			(layers "*.Cu" "*.Mask")
			(remove_unused_layers no)
			(net "Net_8885")
			(clearance 0.0508)
			(thermal_gap 0.0508)
		)
		(pad "P10" thru_hole circle
			(at 19.800062 30.100016 180)
			(size 0.906272 0.906272)
			(drill 0.499872)
			(layers "*.Cu" "*.Mask")
			(remove_unused_layers no)
			(net "GND")
			(clearance 0.0508)
			(thermal_gap 0.0508)
		)
		(pad "Q1" thru_hole circle
			(at 0 31.20009 180)
			(size 0.906272 0.906272)
			(drill 0.499872)
			(layers "*.Cu" "*.Mask")
			(remove_unused_layers no)
			(net "GND")
			(clearance 0.0508)
			(thermal_gap 0.0508)
		)
		(pad "Q3" thru_hole circle
			(at 4.400042 31.20009 180)
			(size 0.906272 0.906272)
			(drill 0.499872)
			(layers "*.Cu" "*.Mask")
			(remove_unused_layers no)
			(net "GND")
			(clearance 0.0508)
			(thermal_gap 0.0508)
		)
		(pad "Q5" thru_hole circle
			(at 8.800084 31.20009 180)
			(size 0.906272 0.906272)
			(drill 0.499872)
			(layers "*.Cu" "*.Mask")
			(remove_unused_layers no)
			(net "GND")
			(clearance 0.0508)
			(thermal_gap 0.0508)
		)
		(pad "Q7" thru_hole circle
			(at 13.199872 31.20009 180)
			(size 0.906272 0.906272)
			(drill 0.499872)
			(layers "*.Cu" "*.Mask")
			(remove_unused_layers no)
			(net "GND")
			(clearance 0.0508)
			(thermal_gap 0.0508)
		)
		(pad "Q9" thru_hole circle
			(at 17.599914 31.20009 180)
			(size 0.906272 0.906272)
			(drill 0.499872)
			(layers "*.Cu" "*.Mask")
			(remove_unused_layers no)
			(net "GND")
			(clearance 0.0508)
			(thermal_gap 0.0508)
		)
		(pad "Q10" thru_hole circle
			(at 19.800062 31.399988 180)
			(size 0.71628 0.71628)
			(drill 0.30988)
			(layers "*.Cu" "*.Mask")
			(remove_unused_layers no)
			(net "Net_8884")
			(clearance 0.0508)
			(thermal_gap 0.0508)
		)
		(pad "R9" thru_hole circle
			(at 17.599914 32.500062 180)
			(size 0.71628 0.71628)
			(drill 0.30988)
			(layers "*.Cu" "*.Mask")
			(remove_unused_layers no)
			(net "Net_8882")
			(clearance 0.0508)
			(thermal_gap 0.0508)
		)
		(pad "R10" thru_hole circle
			(at 19.800062 32.69996 180)
			(size 0.71628 0.71628)
			(drill 0.30988)
			(layers "*.Cu" "*.Mask")
			(remove_unused_layers no)
			(net "Net_8883")
			(clearance 0.0508)
			(thermal_gap 0.0508)
		)
		(pad "S2" thru_hole circle
			(at 2.199894 33.999932 180)
			(size 0.906272 0.906272)
			(drill 0.499872)
			(layers "*.Cu" "*.Mask")
			(remove_unused_layers no)
			(net "GND")
			(clearance 0.0508)
			(thermal_gap 0.0508)
		)
		(pad "S4" thru_hole circle
			(at 6.599936 33.999932 180)
			(size 0.906272 0.906272)
			(drill 0.499872)
			(layers "*.Cu" "*.Mask")
			(remove_unused_layers no)
			(net "GND")
			(clearance 0.0508)
			(thermal_gap 0.0508)
		)
		(pad "S6" thru_hole circle
			(at 10.999978 33.999932 180)
			(size 0.906272 0.906272)
			(drill 0.499872)
			(layers "*.Cu" "*.Mask")
			(remove_unused_layers no)
			(net "GND")
			(clearance 0.0508)
			(thermal_gap 0.0508)
		)
		(pad "S8" thru_hole circle
			(at 15.40002 33.999932 180)
			(size 0.906272 0.906272)
			(drill 0.499872)
			(layers "*.Cu" "*.Mask")
			(remove_unused_layers no)
			(net "GND")
			(clearance 0.0508)
			(thermal_gap 0.0508)
		)
		(pad "S9" thru_hole circle
			(at 17.599914 33.800034 180)
			(size 0.71628 0.71628)
			(drill 0.30988)
			(layers "*.Cu" "*.Mask")
			(remove_unused_layers no)
			(net "Net_8881")
			(clearance 0.0508)
			(thermal_gap 0.0508)
		)
		(pad "S10" thru_hole circle
			(at 19.800062 33.999932 180)
			(size 0.906272 0.906272)
			(drill 0.499872)
			(layers "*.Cu" "*.Mask")
			(remove_unused_layers no)
			(net "GND")
			(clearance 0.0508)
			(thermal_gap 0.0508)
		)
		(pad "T1" thru_hole circle
			(at 0 35.100006 180)
			(size 0.906272 0.906272)
			(drill 0.499872)
			(layers "*.Cu" "*.Mask")
			(remove_unused_layers no)
			(net "GND")
			(clearance 0.0508)
			(thermal_gap 0.0508)
		)
		(pad "T3" thru_hole circle
			(at 4.400042 35.100006 180)
			(size 0.906272 0.906272)
			(drill 0.499872)
			(layers "*.Cu" "*.Mask")
			(remove_unused_layers no)
			(net "GND")
			(clearance 0.0508)
			(thermal_gap 0.0508)
		)
		(pad "T5" thru_hole circle
			(at 8.800084 35.100006 180)
			(size 0.906272 0.906272)
			(drill 0.499872)
			(layers "*.Cu" "*.Mask")
			(remove_unused_layers no)
			(net "GND")
			(clearance 0.0508)
			(thermal_gap 0.0508)
		)
		(pad "T7" thru_hole circle
			(at 13.199872 35.100006 180)
			(size 0.906272 0.906272)
			(drill 0.499872)
			(layers "*.Cu" "*.Mask")
			(remove_unused_layers no)
			(net "GND")
			(clearance 0.0508)
			(thermal_gap 0.0508)
		)
		(pad "T9" thru_hole circle
			(at 17.599914 35.100006 180)
			(size 0.906272 0.906272)
			(drill 0.499872)
			(layers "*.Cu" "*.Mask")
			(remove_unused_layers no)
			(net "GND")
			(clearance 0.0508)
			(thermal_gap 0.0508)
		)
		(pad "T10" thru_hole circle
			(at 19.800062 35.299904 180)
			(size 0.71628 0.71628)
			(drill 0.30988)
			(layers "*.Cu" "*.Mask")
			(remove_unused_layers no)
			(net "Net_8880")
			(clearance 0.0508)
			(thermal_gap 0.0508)
		)
		(pad "U9" thru_hole circle
			(at 17.599914 36.399978 180)
			(size 0.71628 0.71628)
			(drill 0.30988)
			(layers "*.Cu" "*.Mask")
			(remove_unused_layers no)
			(net "Net_8878")
			(clearance 0.0508)
			(thermal_gap 0.0508)
		)
		(pad "U10" thru_hole circle
			(at 19.800062 36.599876 180)
			(size 0.71628 0.71628)
			(drill 0.30988)
			(layers "*.Cu" "*.Mask")
			(remove_unused_layers no)
			(net "Net_8879")
			(clearance 0.0508)
			(thermal_gap 0.0508)
		)
		(pad "V2" thru_hole circle
			(at 2.199894 37.900102 180)
			(size 0.906272 0.906272)
			(drill 0.499872)
			(layers "*.Cu" "*.Mask")
			(remove_unused_layers no)
			(net "GND")
			(clearance 0.0508)
			(thermal_gap 0.0508)
		)
		(pad "V4" thru_hole circle
			(at 6.599936 37.900102 180)
			(size 0.906272 0.906272)
			(drill 0.499872)
			(layers "*.Cu" "*.Mask")
			(remove_unused_layers no)
			(net "GND")
			(clearance 0.0508)
			(thermal_gap 0.0508)
		)
		(pad "V6" thru_hole circle
			(at 10.999978 37.900102 180)
			(size 0.906272 0.906272)
			(drill 0.499872)
			(layers "*.Cu" "*.Mask")
			(remove_unused_layers no)
			(net "GND")
			(clearance 0.0508)
			(thermal_gap 0.0508)
		)
		(pad "V8" thru_hole circle
			(at 15.40002 37.900102 180)
			(size 0.906272 0.906272)
			(drill 0.499872)
			(layers "*.Cu" "*.Mask")
			(remove_unused_layers no)
			(net "GND")
			(clearance 0.0508)
			(thermal_gap 0.0508)
		)
		(pad "V9" thru_hole circle
			(at 17.599914 37.69995 180)
			(size 0.71628 0.71628)
			(drill 0.30988)
			(layers "*.Cu" "*.Mask")
			(remove_unused_layers no)
			(net "Net_8877")
			(clearance 0.0508)
			(thermal_gap 0.0508)
		)
		(pad "V10" thru_hole circle
			(at 19.800062 37.900102 180)
			(size 0.906272 0.906272)
			(drill 0.499872)
			(layers "*.Cu" "*.Mask")
			(remove_unused_layers no)
			(net "GND")
			(clearance 0.0508)
			(thermal_gap 0.0508)
		)
		(pad "W1" thru_hole circle
			(at 0 38.999922 180)
			(size 0.906272 0.906272)
			(drill 0.499872)
			(layers "*.Cu" "*.Mask")
			(remove_unused_layers no)
			(net "GND")
			(clearance 0.0508)
			(thermal_gap 0.0508)
		)
		(pad "W3" thru_hole circle
			(at 4.400042 38.999922 180)
			(size 0.906272 0.906272)
			(drill 0.499872)
			(layers "*.Cu" "*.Mask")
			(remove_unused_layers no)
			(net "GND")
			(clearance 0.0508)
			(thermal_gap 0.0508)
		)
		(pad "W5" thru_hole circle
			(at 8.800084 38.999922 180)
			(size 0.906272 0.906272)
			(drill 0.499872)
			(layers "*.Cu" "*.Mask")
			(remove_unused_layers no)
			(net "GND")
			(clearance 0.0508)
			(thermal_gap 0.0508)
		)
		(pad "W7" thru_hole circle
			(at 13.199872 38.999922 180)
			(size 0.906272 0.906272)
			(drill 0.499872)
			(layers "*.Cu" "*.Mask")
			(remove_unused_layers no)
			(net "GND")
			(clearance 0.0508)
			(thermal_gap 0.0508)
		)
		(pad "W9" thru_hole circle
			(at 17.599914 38.999922 180)
			(size 0.906272 0.906272)
			(drill 0.499872)
			(layers "*.Cu" "*.Mask")
			(remove_unused_layers no)
			(net "GND")
			(clearance 0.0508)
			(thermal_gap 0.0508)
		)
		(pad "W10" thru_hole circle
			(at 19.800062 39.200074 180)
			(size 0.71628 0.71628)
			(drill 0.30988)
			(layers "*.Cu" "*.Mask")
			(remove_unused_layers no)
			(net "Net_8876")
			(clearance 0.0508)
			(thermal_gap 0.0508)
		)
		(pad "X9" thru_hole circle
			(at 17.599914 40.299894 180)
			(size 0.71628 0.71628)
			(drill 0.30988)
			(layers "*.Cu" "*.Mask")
			(remove_unused_layers no)
			(net "Net_8874")
			(clearance 0.0508)
			(thermal_gap 0.0508)
		)
		(pad "X10" thru_hole circle
			(at 19.800062 40.500046 180)
			(size 0.71628 0.71628)
			(drill 0.30988)
			(layers "*.Cu" "*.Mask")
			(remove_unused_layers no)
			(net "Net_8875")
			(clearance 0.0508)
			(thermal_gap 0.0508)
		)
		(pad "Y2" thru_hole circle
			(at 2.199894 41.800018 180)
			(size 0.906272 0.906272)
			(drill 0.499872)
			(layers "*.Cu" "*.Mask")
			(remove_unused_layers no)
			(net "GND")
			(clearance 0.0508)
			(thermal_gap 0.0508)
		)
		(pad "Y4" thru_hole circle
			(at 6.599936 41.800018 180)
			(size 0.906272 0.906272)
			(drill 0.499872)
			(layers "*.Cu" "*.Mask")
			(remove_unused_layers no)
			(net "GND")
			(clearance 0.0508)
			(thermal_gap 0.0508)
		)
		(pad "Y6" thru_hole circle
			(at 10.999978 41.800018 180)
			(size 0.906272 0.906272)
			(drill 0.499872)
			(layers "*.Cu" "*.Mask")
			(remove_unused_layers no)
			(net "GND")
			(clearance 0.0508)
			(thermal_gap 0.0508)
		)
		(pad "Y8" thru_hole circle
			(at 15.40002 41.800018 180)
			(size 0.906272 0.906272)
			(drill 0.499872)
			(layers "*.Cu" "*.Mask")
			(remove_unused_layers no)
			(net "GND")
			(clearance 0.0508)
			(thermal_gap 0.0508)
		)
		(pad "Y9" thru_hole circle
			(at 17.599914 41.60012 180)
			(size 0.71628 0.71628)
			(drill 0.30988)
			(layers "*.Cu" "*.Mask")
			(remove_unused_layers no)
			(net "Net_8873")
			(clearance 0.0508)
			(thermal_gap 0.0508)
		)
		(pad "Y10" thru_hole circle
			(at 19.800062 41.800018 180)
			(size 0.906272 0.906272)
			(drill 0.499872)
			(layers "*.Cu" "*.Mask")
			(remove_unused_layers no)
			(net "GND")
			(clearance 0.0508)
			(thermal_gap 0.0508)
		)
		(pad "Z1" thru_hole circle
			(at 0 42.900092 180)
			(size 0.906272 0.906272)
			(drill 0.499872)
			(layers "*.Cu" "*.Mask")
			(remove_unused_layers no)
			(net "GND")
			(clearance 0.0508)
			(thermal_gap 0.0508)
		)
		(pad "Z2" thru_hole circle
			(at 2.199894 43.09999 180)
			(size 0.71628 0.71628)
			(drill 0.30988)
			(layers "*.Cu" "*.Mask")
			(remove_unused_layers no)
			(net "PRSNT_SWB_B2_N")
			(clearance 0.0508)
			(thermal_gap 0.0508)
		)
		(pad "Z3" thru_hole circle
			(at 4.400042 42.900092 180)
			(size 0.906272 0.906272)
			(drill 0.499872)
			(layers "*.Cu" "*.Mask")
			(remove_unused_layers no)
			(net "GND")
			(clearance 0.0508)
			(thermal_gap 0.0508)
		)
		(pad "Z4" thru_hole circle
			(at 6.599936 43.09999 180)
			(size 0.71628 0.71628)
			(drill 0.30988)
			(layers "*.Cu" "*.Mask")
			(remove_unused_layers no)
			(net "Net_8906")
			(clearance 0.0508)
			(thermal_gap 0.0508)
		)
		(pad "Z5" thru_hole circle
			(at 8.800084 42.900092 180)
			(size 0.906272 0.906272)
			(drill 0.499872)
			(layers "*.Cu" "*.Mask")
			(remove_unused_layers no)
			(net "GND")
			(clearance 0.0508)
			(thermal_gap 0.0508)
		)
		(pad "Z6" thru_hole circle
			(at 10.999978 43.09999 180)
			(size 0.71628 0.71628)
			(drill 0.30988)
			(layers "*.Cu" "*.Mask")
			(remove_unused_layers no)
			(net "Net_8905")
			(clearance 0.0508)
			(thermal_gap 0.0508)
		)
		(pad "Z7" thru_hole circle
			(at 13.199872 42.900092 180)
			(size 0.906272 0.906272)
			(drill 0.499872)
			(layers "*.Cu" "*.Mask")
			(remove_unused_layers no)
			(net "GND")
			(clearance 0.0508)
			(thermal_gap 0.0508)
		)
		(pad "Z8" thru_hole circle
			(at 15.40002 43.09999 180)
			(size 0.71628 0.71628)
			(drill 0.30988)
			(layers "*.Cu" "*.Mask")
			(remove_unused_layers no)
			(net "MB_HSC_EN")
			(clearance 0.0508)
			(thermal_gap 0.0508)
		)
		(pad "Z9" thru_hole circle
			(at 17.599914 42.900092 180)
			(size 0.906272 0.906272)
			(drill 0.499872)
			(layers "*.Cu" "*.Mask")
			(remove_unused_layers no)
			(net "GND")
			(clearance 0.0508)
			(thermal_gap 0.0508)
		)
		(pad "Z10" thru_hole circle
			(at 19.800062 43.09999 180)
			(size 0.71628 0.71628)
			(drill 0.30988)
			(layers "*.Cu" "*.Mask")
			(remove_unused_layers no)
			(net "PRSNT_GPU_A3_R_N")
			(clearance 0.0508)
			(thermal_gap 0.0508)
		)
	)
)
